(kicad_pcb
	(version 20260206)
	(generator "pcbnew")
	(generator_version "10.0")
	(general
		(thickness 1.6)
		(legacy_teardrops no)
	)
	(paper "A4")
	(title_block
		(title "01162023_DA0F0TEBIF0_F0T_Expander_BD_F_brd_V02_OCP.brd")
		(comment 1 "Grand Teton / footprints 7108-7113 of 9728")
	)
	(layers
		(0 "F.Cu" signal "TOP")
		(4 "In1.Cu" signal "GND")
		(6 "In2.Cu" signal "VCC")
		(8 "In3.Cu" signal "VCC1")
		(10 "In4.Cu" signal "GND1")
		(12 "In5.Cu" signal "IN1")
		(14 "In6.Cu" signal "GND2")
		(16 "In7.Cu" signal "IN2")
		(18 "In8.Cu" signal "GND3")
		(20 "In9.Cu" signal "IN3")
		(22 "In10.Cu" signal "GND4")
		(24 "In11.Cu" signal "IN4")
		(26 "In12.Cu" signal "GND5")
		(28 "In13.Cu" signal "IN5")
		(30 "In14.Cu" signal "GND6")
		(32 "In15.Cu" signal "IN6")
		(34 "In16.Cu" signal "GND7")
		(2 "B.Cu" signal "BOTTOM")
		(9 "F.Adhes" user "F.Adhesive")
		(11 "B.Adhes" user "B.Adhesive")
		(13 "F.Paste" user "Package Geometry/Pastemask Top")
		(15 "B.Paste" user "Package Geometry/Pastemask Bottom")
		(5 "F.SilkS" user "Ref Des/Silkscreen Top")
		(7 "B.SilkS" user "Ref Des/Silkscreen Bottom")
		(1 "F.Mask" user "Board Geometry/Soldermask Top")
		(3 "B.Mask" user "Board Geometry/Soldermask Bottom")
		(17 "Dwgs.User" user "User.Drawings")
		(19 "Cmts.User" user "User.Comments")
		(21 "Eco1.User" user "User.Eco1")
		(23 "Eco2.User" user "User.Eco2")
		(25 "Edge.Cuts" user "Board Geometry/Outline")
		(27 "Margin" user)
		(31 "F.CrtYd" user "Package Geometry/Place Bound Top")
		(29 "B.CrtYd" user "Package Geometry/Place Bound Bottom")
		(35 "F.Fab" user "Ref Des/Assembly Top")
		(33 "B.Fab" user "Ref Des/Assembly Bottom")
	)
	(footprint ""
		(layer "F.Cu")
		(at 446.150238 -95.263716 -90)
		(property "Reference" "PR206"
			(at 0 0 270)
			(layer "F.SilkS")
			(hide yes)
			(effects
				(font
					(size 1.27 1.27)
				)
			)
		)
		(property "Value" ""
			(at 0 0 270)
			(layer "F.Fab")
			(effects
				(font
					(size 1.27 1.27)
				)
			)
		)
		(duplicate_pad_numbers_are_jumpers no)
		(fp_line
			(start -0.7874 0.4064)
			(end -0.7874 -0.4064)
			(stroke
				(width 0.1524)
				(type default)
			)
			(layer "F.SilkS")
		)
		(fp_line
			(start 0.7874 0.4064)
			(end -0.7874 0.4064)
			(stroke
				(width 0.1524)
				(type default)
			)
			(layer "F.SilkS")
		)
		(fp_line
			(start -0.7874 -0.4064)
			(end 0.7874 -0.4064)
			(stroke
				(width 0.1524)
				(type default)
			)
			(layer "F.SilkS")
		)
		(fp_line
			(start 0.7874 -0.4064)
			(end 0.7874 0.4064)
			(stroke
				(width 0.1524)
				(type default)
			)
			(layer "F.SilkS")
		)
		(fp_line
			(start -0.67945 0.3048)
			(end -0.67945 -0.305054)
			(stroke
				(width 0.1)
				(type default)
			)
			(layer "F.Fab")
		)
		(fp_line
			(start -0.12065 0.3048)
			(end -0.67945 0.3048)
			(stroke
				(width 0.1)
				(type default)
			)
			(layer "F.Fab")
		)
		(fp_line
			(start 0.120396 0.3048)
			(end 0.120396 0.2794)
			(stroke
				(width 0.1)
				(type default)
			)
			(layer "F.Fab")
		)
		(fp_line
			(start 0.67945 0.3048)
			(end 0.120396 0.3048)
			(stroke
				(width 0.1)
				(type default)
			)
			(layer "F.Fab")
		)
		(fp_line
			(start -0.12065 0.2794)
			(end -0.12065 0.3048)
			(stroke
				(width 0.1)
				(type default)
			)
			(layer "F.Fab")
		)
		(fp_line
			(start 0.120396 0.2794)
			(end -0.12065 0.2794)
			(stroke
				(width 0.1)
				(type default)
			)
			(layer "F.Fab")
		)
		(fp_line
			(start -0.12065 -0.2794)
			(end 0.12065 -0.2794)
			(stroke
				(width 0.1)
				(type default)
			)
			(layer "F.Fab")
		)
		(fp_line
			(start 0.12065 -0.2794)
			(end 0.12065 -0.3048)
			(stroke
				(width 0.1)
				(type default)
			)
			(layer "F.Fab")
		)
		(fp_line
			(start 0.12065 -0.3048)
			(end 0.67945 -0.3048)
			(stroke
				(width 0.1)
				(type default)
			)
			(layer "F.Fab")
		)
		(fp_line
			(start 0.67945 -0.3048)
			(end 0.67945 0.3048)
			(stroke
				(width 0.1)
				(type default)
			)
			(layer "F.Fab")
		)
		(fp_line
			(start -0.67945 -0.305054)
			(end -0.12065 -0.305054)
			(stroke
				(width 0.1)
				(type default)
			)
			(layer "F.Fab")
		)
		(fp_line
			(start -0.12065 -0.305054)
			(end -0.12065 -0.2794)
			(stroke
				(width 0.1)
				(type default)
			)
			(layer "F.Fab")
		)
		(pad "1" smd circle
			(at -0.40005 0 270)
			(size 0 0)
			(layers "F.Cu" "F.Mask" "F.Paste")
			(net "P12V_NIC7_OCP")
		)
		(pad "2" smd circle
			(at 0.40005 0 270)
			(size 0 0)
			(layers "F.Cu" "F.Mask" "F.Paste")
			(net "GND")
		)
	)
	(footprint ""
		(layer "F.Cu")
		(at 265.5951 -77.279754 -90)
		(property "Reference" "R1049"
			(at 0 0 270)
			(layer "F.SilkS")
			(hide yes)
			(effects
				(font
					(size 1.27 1.27)
				)
			)
		)
		(property "Value" ""
			(at 0 0 270)
			(layer "F.Fab")
			(effects
				(font
					(size 1.27 1.27)
				)
			)
		)
		(duplicate_pad_numbers_are_jumpers no)
		(fp_line
			(start -0.7874 0.4064)
			(end -0.7874 -0.4064)
			(stroke
				(width 0.1524)
				(type default)
			)
			(layer "F.SilkS")
		)
		(fp_line
			(start 0.7874 0.4064)
			(end -0.7874 0.4064)
			(stroke
				(width 0.1524)
				(type default)
			)
			(layer "F.SilkS")
		)
		(fp_line
			(start -0.7874 -0.4064)
			(end 0.7874 -0.4064)
			(stroke
				(width 0.1524)
				(type default)
			)
			(layer "F.SilkS")
		)
		(fp_line
			(start 0.7874 -0.4064)
			(end 0.7874 0.4064)
			(stroke
				(width 0.1524)
				(type default)
			)
			(layer "F.SilkS")
		)
		(fp_line
			(start -0.67945 0.3048)
			(end -0.67945 -0.305054)
			(stroke
				(width 0.1)
				(type default)
			)
			(layer "F.Fab")
		)
		(fp_line
			(start -0.12065 0.3048)
			(end -0.67945 0.3048)
			(stroke
				(width 0.1)
				(type default)
			)
			(layer "F.Fab")
		)
		(fp_line
			(start 0.120396 0.3048)
			(end 0.120396 0.2794)
			(stroke
				(width 0.1)
				(type default)
			)
			(layer "F.Fab")
		)
		(fp_line
			(start 0.67945 0.3048)
			(end 0.120396 0.3048)
			(stroke
				(width 0.1)
				(type default)
			)
			(layer "F.Fab")
		)
		(fp_line
			(start -0.12065 0.2794)
			(end -0.12065 0.3048)
			(stroke
				(width 0.1)
				(type default)
			)
			(layer "F.Fab")
		)
		(fp_line
			(start 0.120396 0.2794)
			(end -0.12065 0.2794)
			(stroke
				(width 0.1)
				(type default)
			)
			(layer "F.Fab")
		)
		(fp_line
			(start -0.12065 -0.2794)
			(end 0.12065 -0.2794)
			(stroke
				(width 0.1)
				(type default)
			)
			(layer "F.Fab")
		)
		(fp_line
			(start 0.12065 -0.2794)
			(end 0.12065 -0.3048)
			(stroke
				(width 0.1)
				(type default)
			)
			(layer "F.Fab")
		)
		(fp_line
			(start 0.12065 -0.3048)
			(end 0.67945 -0.3048)
			(stroke
				(width 0.1)
				(type default)
			)
			(layer "F.Fab")
		)
		(fp_line
			(start 0.67945 -0.3048)
			(end 0.67945 0.3048)
			(stroke
				(width 0.1)
				(type default)
			)
			(layer "F.Fab")
		)
		(fp_line
			(start -0.67945 -0.305054)
			(end -0.12065 -0.305054)
			(stroke
				(width 0.1)
				(type default)
			)
			(layer "F.Fab")
		)
		(fp_line
			(start -0.12065 -0.305054)
			(end -0.12065 -0.2794)
			(stroke
				(width 0.1)
				(type default)
			)
			(layer "F.Fab")
		)
		(pad "1" smd circle
			(at -0.40005 0 270)
			(size 0 0)
			(layers "F.Cu" "F.Mask" "F.Paste")
			(net "CLK_BUFFER_9ZXL0851E_8_15_OE2_N")
		)
		(pad "2" smd circle
			(at 0.40005 0 270)
			(size 0 0)
			(layers "F.Cu" "F.Mask" "F.Paste")
			(net "P3V3")
		)
	)
	(footprint ""
		(layer "F.Cu")
		(at 372.913656 -239.647984)
		(property "Reference" "R6402"
			(at 0 0 0)
			(layer "F.SilkS")
			(hide yes)
			(effects
				(font
					(size 1.27 1.27)
				)
			)
		)
		(property "Value" ""
			(at 0 0 0)
			(layer "F.Fab")
			(effects
				(font
					(size 1.27 1.27)
				)
			)
		)
		(duplicate_pad_numbers_are_jumpers no)
		(fp_line
			(start -0.7874 -0.4064)
			(end 0.7874 -0.4064)
			(stroke
				(width 0.1524)
				(type default)
			)
			(layer "F.SilkS")
		)
		(fp_line
			(start -0.7874 0.4064)
			(end -0.7874 -0.4064)
			(stroke
				(width 0.1524)
				(type default)
			)
			(layer "F.SilkS")
		)
		(fp_line
			(start 0.7874 -0.4064)
			(end 0.7874 0.4064)
			(stroke
				(width 0.1524)
				(type default)
			)
			(layer "F.SilkS")
		)
		(fp_line
			(start 0.7874 0.4064)
			(end -0.7874 0.4064)
			(stroke
				(width 0.1524)
				(type default)
			)
			(layer "F.SilkS")
		)
		(fp_line
			(start -0.67945 -0.305054)
			(end -0.12065 -0.305054)
			(stroke
				(width 0.1)
				(type default)
			)
			(layer "F.Fab")
		)
		(fp_line
			(start -0.67945 0.3048)
			(end -0.67945 -0.305054)
			(stroke
				(width 0.1)
				(type default)
			)
			(layer "F.Fab")
		)
		(fp_line
			(start -0.12065 -0.305054)
			(end -0.12065 -0.2794)
			(stroke
				(width 0.1)
				(type default)
			)
			(layer "F.Fab")
		)
		(fp_line
			(start -0.12065 -0.2794)
			(end 0.12065 -0.2794)
			(stroke
				(width 0.1)
				(type default)
			)
			(layer "F.Fab")
		)
		(fp_line
			(start -0.12065 0.2794)
			(end -0.12065 0.3048)
			(stroke
				(width 0.1)
				(type default)
			)
			(layer "F.Fab")
		)
		(fp_line
			(start -0.12065 0.3048)
			(end -0.67945 0.3048)
			(stroke
				(width 0.1)
				(type default)
			)
			(layer "F.Fab")
		)
		(fp_line
			(start 0.120396 0.2794)
			(end -0.12065 0.2794)
			(stroke
				(width 0.1)
				(type default)
			)
			(layer "F.Fab")
		)
		(fp_line
			(start 0.120396 0.3048)
			(end 0.120396 0.2794)
			(stroke
				(width 0.1)
				(type default)
			)
			(layer "F.Fab")
		)
		(fp_line
			(start 0.12065 -0.3048)
			(end 0.67945 -0.3048)
			(stroke
				(width 0.1)
				(type default)
			)
			(layer "F.Fab")
		)
		(fp_line
			(start 0.12065 -0.2794)
			(end 0.12065 -0.3048)
			(stroke
				(width 0.1)
				(type default)
			)
			(layer "F.Fab")
		)
		(fp_line
			(start 0.67945 -0.3048)
			(end 0.67945 0.3048)
			(stroke
				(width 0.1)
				(type default)
			)
			(layer "F.Fab")
		)
		(fp_line
			(start 0.67945 0.3048)
			(end 0.120396 0.3048)
			(stroke
				(width 0.1)
				(type default)
			)
			(layer "F.Fab")
		)
		(pad "1" smd circle
			(at -0.40005 0)
			(size 0 0)
			(layers "F.Cu" "F.Mask" "F.Paste")
			(net "PWRGD_P12V_AUX_BUF")
		)
		(pad "2" smd circle
			(at 0.40005 0)
			(size 0 0)
			(layers "F.Cu" "F.Mask" "F.Paste")
			(net "PWRGD_P12V_AUX_BUF_R")
		)
	)
	(footprint ""
		(layer "B.Cu")
		(at 397.85544 -154.0256)
		(property "Reference" "R327"
			(at 0 0 0)
			(layer "B.SilkS")
			(hide yes)
			(effects
				(font
					(size 1.27 1.27)
				)
				(justify mirror)
			)
		)
		(property "Value" ""
			(at 0 0 0)
			(layer "B.Fab")
			(effects
				(font
					(size 1.27 1.27)
				)
				(justify mirror)
			)
		)
		(duplicate_pad_numbers_are_jumpers no)
		(fp_line
			(start -0.7874 -0.4064)
			(end -0.7874 0.4064)
			(stroke
				(width 0.1524)
				(type default)
			)
			(layer "B.SilkS")
		)
		(fp_line
			(start -0.7874 0.4064)
			(end 0.7874 0.4064)
			(stroke
				(width 0.1524)
				(type default)
			)
			(layer "B.SilkS")
		)
		(fp_line
			(start 0.7874 -0.4064)
			(end -0.7874 -0.4064)
			(stroke
				(width 0.1524)
				(type default)
			)
			(layer "B.SilkS")
		)
		(fp_line
			(start 0.7874 0.4064)
			(end 0.7874 -0.4064)
			(stroke
				(width 0.1524)
				(type default)
			)
			(layer "B.SilkS")
		)
		(fp_line
			(start -0.67945 -0.3048)
			(end -0.67945 0.3048)
			(stroke
				(width 0.1)
				(type default)
			)
			(layer "B.Fab")
		)
		(fp_line
			(start -0.67945 0.3048)
			(end -0.120396 0.3048)
			(stroke
				(width 0.1)
				(type default)
			)
			(layer "B.Fab")
		)
		(fp_line
			(start -0.12065 -0.3048)
			(end -0.67945 -0.3048)
			(stroke
				(width 0.1)
				(type default)
			)
			(layer "B.Fab")
		)
		(fp_line
			(start -0.12065 -0.2794)
			(end -0.12065 -0.3048)
			(stroke
				(width 0.1)
				(type default)
			)
			(layer "B.Fab")
		)
		(fp_line
			(start -0.120396 0.2794)
			(end 0.12065 0.2794)
			(stroke
				(width 0.1)
				(type default)
			)
			(layer "B.Fab")
		)
		(fp_line
			(start -0.120396 0.3048)
			(end -0.120396 0.2794)
			(stroke
				(width 0.1)
				(type default)
			)
			(layer "B.Fab")
		)
		(fp_line
			(start 0.12065 -0.305054)
			(end 0.12065 -0.2794)
			(stroke
				(width 0.1)
				(type default)
			)
			(layer "B.Fab")
		)
		(fp_line
			(start 0.12065 -0.2794)
			(end -0.12065 -0.2794)
			(stroke
				(width 0.1)
				(type default)
			)
			(layer "B.Fab")
		)
		(fp_line
			(start 0.12065 0.2794)
			(end 0.12065 0.3048)
			(stroke
				(width 0.1)
				(type default)
			)
			(layer "B.Fab")
		)
		(fp_line
			(start 0.12065 0.3048)
			(end 0.67945 0.3048)
			(stroke
				(width 0.1)
				(type default)
			)
			(layer "B.Fab")
		)
		(fp_line
			(start 0.67945 -0.305054)
			(end 0.12065 -0.305054)
			(stroke
				(width 0.1)
				(type default)
			)
			(layer "B.Fab")
		)
		(fp_line
			(start 0.67945 0.3048)
			(end 0.67945 -0.305054)
			(stroke
				(width 0.1)
				(type default)
			)
			(layer "B.Fab")
		)
		(pad "1" smd circle
			(at 0.40005 0 180)
			(size 0 0)
			(layers "B.Cu" "B.Mask" "B.Paste")
			(net "NCSI_NIC6_TX_EN")
		)
		(pad "2" smd circle
			(at -0.40005 0 180)
			(size 0 0)
			(layers "B.Cu" "B.Mask" "B.Paste")
			(net "GND")
		)
	)
	(footprint ""
		(layer "B.Cu")
		(at 338.266024 20.575524 180)
		(property "Reference" "DE06F_1"
			(at -2.195576 -3.047746 0)
			(unlocked yes)
			(layer "B.SilkS")
			(effects
				(font
					(size 0.7874 0.5842)
					(thickness 0.1524)
				)
				(justify left mirror)
			)
		)
		(property "Value" ""
			(at 0 0 0)
			(layer "B.Fab")
			(effects
				(font
					(size 1.27 1.27)
				)
				(justify mirror)
			)
		)
		(duplicate_pad_numbers_are_jumpers no)
		(fp_line
			(start 1.2192 2.1082)
			(end 1.2192 -2.1082)
			(stroke
				(width 0.1524)
				(type default)
			)
			(layer "B.SilkS")
		)
		(fp_line
			(start 1.2192 -2.1082)
			(end -1.2192 -2.1082)
			(stroke
				(width 0.1524)
				(type default)
			)
			(layer "B.SilkS")
		)
		(fp_line
			(start -1.2192 2.1082)
			(end 1.2192 2.1082)
			(stroke
				(width 0.1524)
				(type default)
			)
			(layer "B.SilkS")
		)
		(fp_line
			(start -1.2192 -2.1082)
			(end -1.2192 2.1082)
			(stroke
				(width 0.1524)
				(type default)
			)
			(layer "B.SilkS")
		)
		(pad "" np_thru_hole circle
			(at -3.4671 -1.27 90)
			(size 1.0414 1.0414)
			(drill 1.0414)
			(layers "*.Cu" "*.Mask")
			(clearance 0.381)
			(thermal_gap 0.381)
		)
		(pad "" np_thru_hole circle
			(at -3.4671 1.27 90)
			(size 1.0414 1.0414)
			(drill 1.0414)
			(layers "*.Cu" "*.Mask")
			(clearance 0.381)
			(thermal_gap 0.381)
		)
		(pad "" np_thru_hole circle
			(at 2.8829 -1.27 90)
			(size 1.0414 1.0414)
			(drill 1.0414)
			(layers "*.Cu" "*.Mask")
			(clearance 0.381)
			(thermal_gap 0.381)
		)
		(pad "" np_thru_hole circle
			(at 2.8829 1.27 90)
			(size 1.0414 1.0414)
			(drill 1.0414)
			(layers "*.Cu" "*.Mask")
			(clearance 0.381)
			(thermal_gap 0.381)
		)
		(pad "1" smd rect
			(at -0.8255 -0.249936 90)
			(size 0.3048 0.508)
			(layers "B.Cu" "B.Mask" "B.Paste")
			(net "85_5INCH_IN4_DP")
		)
		(pad "2" smd rect
			(at -0.8255 0.249936 90)
			(size 0.3048 0.508)
			(layers "B.Cu" "B.Mask" "B.Paste")
			(net "85_5INCH_IN4_DN")
		)
		(pad "3" smd circle
			(at 0 0)
			(size 0 0)
			(layers "B.Cu" "B.Mask" "B.Paste")
			(net "COUPON_GND2")
		)
		(zone
			(layers "F.Cu" "B.Cu" "In1.Cu" "In2.Cu" "In3.Cu" "In4.Cu" "In5.Cu" "In6.Cu"
				"In7.Cu" "In8.Cu" "In9.Cu" "In10.Cu" "In11.Cu" "In12.Cu" "In13.Cu" "In14.Cu"
				"In15.Cu" "In16.Cu"
			)
			(hatch none 0.5)
			(connect_pads
				(clearance 0)
			)
			(min_thickness 0.25)
			(keepout
				(tracks not_allowed)
				(vias allowed)
				(pads allowed)
				(copperpour not_allowed)
				(footprints allowed)
			)
			(placement
				(enabled no)
				(sheetname "")
			)
			(fill
				(thermal_gap 0.5)
				(thermal_bridge_width 0.5)
				(island_removal_mode 0)
			)
			(polygon
				(pts
					(arc
						(start 336.310224 19.305524)
						(mid 334.456024 19.305524)
						(end 336.310224 19.305524)
					)
				)
			)
		)
		(zone
			(layers "F.Cu" "B.Cu" "In1.Cu" "In2.Cu" "In3.Cu" "In4.Cu" "In5.Cu" "In6.Cu"
				"In7.Cu" "In8.Cu" "In9.Cu" "In10.Cu" "In11.Cu" "In12.Cu" "In13.Cu" "In14.Cu"
				"In15.Cu" "In16.Cu"
			)
			(hatch none 0.5)
			(connect_pads
				(clearance 0)
			)
			(min_thickness 0.25)
			(keepout
				(tracks not_allowed)
				(vias allowed)
				(pads allowed)
				(copperpour not_allowed)
				(footprints allowed)
			)
			(placement
				(enabled no)
				(sheetname "")
			)
			(fill
				(thermal_gap 0.5)
				(thermal_bridge_width 0.5)
				(island_removal_mode 0)
			)
			(polygon
				(pts
					(arc
						(start 336.310224 21.845524)
						(mid 334.456024 21.845524)
						(end 336.310224 21.845524)
					)
				)
			)
		)
		(zone
			(layers "F.Cu" "B.Cu" "In1.Cu" "In2.Cu" "In3.Cu" "In4.Cu" "In5.Cu" "In6.Cu"
				"In7.Cu" "In8.Cu" "In9.Cu" "In10.Cu" "In11.Cu" "In12.Cu" "In13.Cu" "In14.Cu"
				"In15.Cu" "In16.Cu"
			)
			(hatch none 0.5)
			(connect_pads
				(clearance 0)
			)
			(min_thickness 0.25)
			(keepout
				(tracks not_allowed)
				(vias allowed)
				(pads allowed)
				(copperpour not_allowed)
				(footprints allowed)
			)
			(placement
				(enabled no)
				(sheetname "")
			)
			(fill
				(thermal_gap 0.5)
				(thermal_bridge_width 0.5)
				(island_removal_mode 0)
			)
			(polygon
				(pts
					(arc
						(start 342.660224 19.305524)
						(mid 340.806024 19.305524)
						(end 342.660224 19.305524)
					)
				)
			)
		)
		(zone
			(layers "F.Cu" "B.Cu" "In1.Cu" "In2.Cu" "In3.Cu" "In4.Cu" "In5.Cu" "In6.Cu"
				"In7.Cu" "In8.Cu" "In9.Cu" "In10.Cu" "In11.Cu" "In12.Cu" "In13.Cu" "In14.Cu"
				"In15.Cu" "In16.Cu"
			)
			(hatch none 0.5)
			(connect_pads
				(clearance 0)
			)
			(min_thickness 0.25)
			(keepout
				(tracks not_allowed)
				(vias allowed)
				(pads allowed)
				(copperpour not_allowed)
				(footprints allowed)
			)
			(placement
				(enabled no)
				(sheetname "")
			)
			(fill
				(thermal_gap 0.5)
				(thermal_bridge_width 0.5)
				(island_removal_mode 0)
			)
			(polygon
				(pts
					(arc
						(start 342.660224 21.845524)
						(mid 340.806024 21.845524)
						(end 342.660224 21.845524)
					)
				)
			)
		)
		(zone
			(layer "B.Cu")
			(hatch none 0.5)
			(connect_pads
				(clearance 0)
			)
			(min_thickness 0.25)
			(keepout
				(tracks not_allowed)
				(vias allowed)
				(pads allowed)
				(copperpour not_allowed)
				(footprints allowed)
			)
			(placement
				(enabled no)
				(sheetname "")
			)
			(fill
				(thermal_gap 0.5)
				(thermal_bridge_width 0.5)
				(island_removal_mode 0)
			)
			(polygon
				(pts
					(xy 339.383624 21.124164) (xy 339.383624 21.02866) (xy 338.786724 21.02866) (xy 338.786724 20.62226)
					(xy 339.383624 20.62226) (xy 339.383624 20.528788) (xy 338.786724 20.528788) (xy 338.786724 20.122388)
					(xy 339.383624 20.122388) (xy 339.383624 20.026884) (xy 338.685124 20.026884) (xy 338.685124 21.124164)
				)
			)
		)
	)
	(footprint ""
		(layer "B.Cu")
		(at 59.649868 -290.199826 90)
		(property "Reference" "C1212"
			(at 0 0 90)
			(layer "B.SilkS")
			(hide yes)
			(effects
				(font
					(size 1.27 1.27)
				)
				(justify mirror)
			)
		)
		(property "Value" ""
			(at 0 0 90)
			(layer "B.Fab")
			(effects
				(font
					(size 1.27 1.27)
				)
				(justify mirror)
			)
		)
		(duplicate_pad_numbers_are_jumpers no)
		(fp_line
			(start 0.299974 -0.150114)
			(end -0.299974 -0.150114)
			(stroke
				(width 0.1)
				(type default)
			)
			(layer "B.Fab")
		)
		(fp_line
			(start -0.299974 -0.150114)
			(end -0.299974 0.150114)
			(stroke
				(width 0.1)
				(type default)
			)
			(layer "B.Fab")
		)
		(fp_line
			(start 0.299974 0.150114)
			(end 0.299974 -0.150114)
			(stroke
				(width 0.1)
				(type default)
			)
			(layer "B.Fab")
		)
		(fp_line
			(start -0.299974 0.150114)
			(end 0.299974 0.150114)
			(stroke
				(width 0.1)
				(type default)
			)
			(layer "B.Fab")
		)
		(pad "1" smd rect
			(at 0.2667 0 270)
			(size 0.3048 0.381)
			(layers "B.Cu" "B.Mask" "B.Paste")
			(net "P0V8_SERDES_VDDA_PEX0")
		)
		(pad "2" smd rect
			(at -0.2667 0 270)
			(size 0.3048 0.381)
			(layers "B.Cu" "B.Mask" "B.Paste")
			(net "GND")
		)
	)
)
